(kicad_pcb
	(version 20241229)
	(generator "pcbnew")
	(generator_version "9.0")
	(general
		(thickness 1.6)
		(legacy_teardrops no)
	)
	(paper "A4")
	(title_block
		(title "GMSL Deserializer")
		(date "2025-10-09")
		(rev "1.0.4")
		(company "Antmicro Ltd")
		(comment 1 "www.antmicro.com")
		(comment 9 "footprints 14-14 of 235")
	)
	(layers
		(0 "F.Cu" signal)
		(4 "In1.Cu" power)
		(6 "In2.Cu" power)
		(2 "B.Cu" signal)
		(9 "F.Adhes" user "F.Adhesive")
		(11 "B.Adhes" user "B.Adhesive")
		(13 "F.Paste" user)
		(15 "B.Paste" user)
		(5 "F.SilkS" user "F.Silkscreen")
		(7 "B.SilkS" user "B.Silkscreen")
		(1 "F.Mask" user)
		(3 "B.Mask" user)
		(17 "Dwgs.User" user "User.Drawings")
		(19 "Cmts.User" user "User.Comments")
		(21 "Eco1.User" user "User.Eco1")
		(23 "Eco2.User" user "User.Eco2")
		(25 "Edge.Cuts" user)
		(27 "Margin" user)
		(31 "F.CrtYd" user "F.Courtyard")
		(29 "B.CrtYd" user "B.Courtyard")
		(35 "F.Fab" user)
		(33 "B.Fab" user)
	)
	(footprint "antmicro-footprints:QFN-56-1EP_8x8mm_P0.5mm_EP4.8x4.8mm"
		(layer "F.Cu")
		(at 146.558 81.620528 -135)
		(descr "T5688Y+6C")
		(tags "QFN")
		(property "Reference" "U7"
			(at -4.228023 -5.434732 225)
			(layer "F.SilkS")
			(effects
				(font
					(size 0.7 0.7)
					(thickness 0.15)
				)
				(justify right bottom)
			)
		)
		(property "Value" "MAX96724GTN_VY+"
			(at 0 5.32 45)
			(layer "F.Fab")
			(effects
				(font
					(size 0.7 0.7)
					(thickness 0.15)
				)
				(justify right bottom)
			)
		)
		(property "Datasheet" "https://www.mouser.com/datasheet/2/609/max96724-3135154.pdf"
			(at 0 0 225)
			(layer "F.Fab")
			(hide yes)
			(effects
				(font
					(size 1.27 1.27)
					(thickness 0.15)
				)
			)
		)
		(property "Description" "ADI GMSL2/1 Tunneling Quad Deserializer 6GHz with 2x4 or 4x2 MIPI DPHY/CPHY Outputs"
			(at 0 0 225)
			(layer "F.Fab")
			(hide yes)
			(effects
				(font
					(size 1.27 1.27)
					(thickness 0.15)
				)
			)
		)
		(property "Author" "Antmicro"
			(at 192.475727 242.967112 0)
			(layer "F.Fab")
			(hide yes)
			(effects
				(font
					(size 1 1)
					(thickness 0.15)
				)
			)
		)
		(property "License" "Apache-2.0"
			(at 192.475727 242.967112 0)
			(layer "F.Fab")
			(hide yes)
			(effects
				(font
					(size 1 1)
					(thickness 0.15)
				)
			)
		)
		(property "MPN" "MAX96724GTN/VY+"
			(at 192.475727 242.967112 0)
			(layer "F.Fab")
			(hide yes)
			(effects
				(font
					(size 1 1)
					(thickness 0.15)
				)
			)
		)
		(property "Manufacturer" "Analog Devices"
			(at 192.475727 242.967112 0)
			(layer "F.Fab")
			(hide yes)
			(effects
				(font
					(size 1 1)
					(thickness 0.15)
				)
			)
		)
		(sheetname "/Deserializer/")
		(sheetfile "deserializer.kicad_sch")
		(attr smd)
		(fp_line
			(start 4.11 4.11)
			(end 4.11 3.634)
			(stroke
				(width 0.15)
				(type solid)
			)
			(layer "F.SilkS")
		)
		(fp_line
			(start 3.634 4.11)
			(end 4.11 4.11)
			(stroke
				(width 0.15)
				(type solid)
			)
			(layer "F.SilkS")
		)
		(fp_line
			(start -3.635 4.11)
			(end -4.111 4.11)
			(stroke
				(width 0.15)
				(type solid)
			)
			(layer "F.SilkS")
		)
		(fp_line
			(start -4.111 4.11)
			(end -4.111 3.634)
			(stroke
				(width 0.15)
				(type solid)
			)
			(layer "F.SilkS")
		)
		(fp_line
			(start 4.11 -4.111)
			(end 4.11 -3.635)
			(stroke
				(width 0.15)
				(type solid)
			)
			(layer "F.SilkS")
		)
		(fp_line
			(start 3.634 -4.111)
			(end 4.11 -4.111)
			(stroke
				(width 0.15)
				(type solid)
			)
			(layer "F.SilkS")
		)
		(fp_line
			(start -4.111 -3.635)
			(end -4.111 -4.111)
			(stroke
				(width 0.15)
				(type solid)
			)
			(layer "F.SilkS")
		)
		(fp_line
			(start -3.635 -4.111)
			(end -4.111 -4.111)
			(stroke
				(width 0.15)
				(type solid)
			)
			(layer "F.SilkS")
		)
		(fp_circle
			(center -4.6 -3.25)
			(end -4.55 -3.25)
			(stroke
				(width 0.15)
				(type solid)
			)
			(fill yes)
			(layer "F.SilkS")
		)
		(fp_poly
			(pts
				(xy 4.5 4.5) (xy -4.5 4.5) (xy -4.5 -4.5) (xy 4.5 -4.5)
			)
			(stroke
				(width 0.05)
				(type solid)
			)
			(fill no)
			(layer "F.CrtYd")
		)
		(fp_poly
			(pts
				(xy -4.05 -4.05) (xy 4.05 -4.05) (xy 4.05 4.05) (xy -4.05 4.05)
			)
			(stroke
				(width 0.15)
				(type solid)
			)
			(fill no)
			(layer "F.Fab")
		)
		(pad "" smd roundrect
			(at -1.8 -1.8 225)
			(size 0.8 0.8)
			(layers "F.Paste")
			(roundrect_rratio 0.221239)
		)
		(pad "" smd roundrect
			(at -1.8 -0.6 225)
			(size 0.8 0.8)
			(layers "F.Paste")
			(roundrect_rratio 0.221239)
		)
		(pad "" smd roundrect
			(at -1.8 0.6 225)
			(size 0.8 0.8)
			(layers "F.Paste")
			(roundrect_rratio 0.221239)
		)
		(pad "" smd roundrect
			(at -1.8 1.8 225)
			(size 0.8 0.8)
			(layers "F.Paste")
			(roundrect_rratio 0.221239)
		)
		(pad "" smd roundrect
			(at -0.6 -1.8 225)
			(size 0.8 0.8)
			(layers "F.Paste")
			(roundrect_rratio 0.221239)
		)
		(pad "" smd roundrect
			(at -0.6 -0.6 225)
			(size 0.8 0.8)
			(layers "F.Paste")
			(roundrect_rratio 0.221239)
		)
		(pad "" smd roundrect
			(at -0.6 0.6 225)
			(size 0.8 0.8)
			(layers "F.Paste")
			(roundrect_rratio 0.221239)
		)
		(pad "" smd roundrect
			(at -0.6 1.8 225)
			(size 0.8 0.8)
			(layers "F.Paste")
			(roundrect_rratio 0.221239)
		)
		(pad "" smd roundrect
			(at 0.6 -1.8 225)
			(size 0.8 0.8)
			(layers "F.Paste")
			(roundrect_rratio 0.221239)
		)
		(pad "" smd roundrect
			(at 0.6 -0.6 225)
			(size 0.8 0.8)
			(layers "F.Paste")
			(roundrect_rratio 0.221239)
		)
		(pad "" smd roundrect
			(at 0.6 0.6 225)
			(size 0.8 0.8)
			(layers "F.Paste")
			(roundrect_rratio 0.221239)
		)
		(pad "" smd roundrect
			(at 0.6 1.8 225)
			(size 0.8 0.8)
			(layers "F.Paste")
			(roundrect_rratio 0.221239)
		)
		(pad "" smd roundrect
			(at 1.8 -1.8 225)
			(size 0.8 0.8)
			(layers "F.Paste")
			(roundrect_rratio 0.221239)
		)
		(pad "" smd roundrect
			(at 1.8 -0.6 225)
			(size 0.8 0.8)
			(layers "F.Paste")
			(roundrect_rratio 0.221239)
		)
		(pad "" smd roundrect
			(at 1.8 0.6 225)
			(size 0.8 0.8)
			(layers "F.Paste")
			(roundrect_rratio 0.221239)
		)
		(pad "" smd roundrect
			(at 1.8 1.8 225)
			(size 0.8 0.8)
			(layers "F.Paste")
			(roundrect_rratio 0.221239)
		)
		(pad "1" smd roundrect
			(at -4 -3.25 225)
			(size 0.8 0.3)
			(layers "F.Cu" "F.Mask" "F.Paste")
			(roundrect_rratio 0.25)
			(net 80 "/Connectors/MFP0")
			(pinfunction "MFP0")
			(pintype "passive")
		)
		(pad "2" smd roundrect
			(at -4 -2.75 225)
			(size 0.8 0.3)
			(layers "F.Cu" "F.Mask" "F.Paste")
			(roundrect_rratio 0.25)
			(net 81 "/Connectors/MFP1")
			(pinfunction "MFP1")
			(pintype "passive")
		)
		(pad "3" smd roundrect
			(at -4 -2.25 225)
			(size 0.8 0.3)
			(layers "F.Cu" "F.Mask" "F.Paste")
			(roundrect_rratio 0.25)
			(net 82 "/Connectors/MFP2")
			(pinfunction "MFP2")
			(pintype "passive")
		)
		(pad "4" smd roundrect
			(at -4 -1.75 225)
			(size 0.8 0.3)
			(layers "F.Cu" "F.Mask" "F.Paste")
			(roundrect_rratio 0.25)
			(net 76 "/Deserializer/CFG0")
			(pinfunction "CFG0")
			(pintype "passive")
		)
		(pad "5" smd roundrect
			(at -4.000001 -1.25 225)
			(size 0.8 0.3)
			(layers "F.Cu" "F.Mask" "F.Paste")
			(roundrect_rratio 0.25)
			(net 16 "/Deserializer/SIOD_P")
			(pinfunction "SIOD_P")
			(pintype "passive")
		)
		(pad "6" smd roundrect
			(at -4 -0.75 225)
			(size 0.8 0.3)
			(layers "F.Cu" "F.Mask" "F.Paste")
			(roundrect_rratio 0.25)
			(net 24 "/Deserializer/SIOD_N")
			(pinfunction "SIOD_N")
			(pintype "passive")
		)
		(pad "7" smd roundrect
			(at -4 -0.25 225)
			(size 0.8 0.3)
			(layers "F.Cu" "F.Mask" "F.Paste")
			(roundrect_rratio 0.25)
			(net 26 "/Deserializer/VDD_1.8V")
			(pinfunction "VDD_1.8V")
			(pintype "passive")
		)
		(pad "8" smd roundrect
			(at -4 0.25 225)
			(size 0.8 0.3)
			(layers "F.Cu" "F.Mask" "F.Paste")
			(roundrect_rratio 0.25)
			(net 28 "/Deserializer/CAP_VDD")
			(pinfunction "CAP_VDD")
			(pintype "passive")
		)
		(pad "9" smd roundrect
			(at -4 0.75 225)
			(size 0.8 0.3)
			(layers "F.Cu" "F.Mask" "F.Paste")
			(roundrect_rratio 0.25)
			(net 22 "/Deserializer/SIOC_N")
			(pinfunction "SIOC_N")
			(pintype "passive")
		)
		(pad "10" smd roundrect
			(at -4.000001 1.25 225)
			(size 0.8 0.3)
			(layers "F.Cu" "F.Mask" "F.Paste")
			(roundrect_rratio 0.25)
			(net 15 "/Deserializer/SIOC_P")
			(pinfunction "SIOC_P")
			(pintype "passive")
		)
		(pad "11" smd roundrect
			(at -4 1.75 225)
			(size 0.8 0.3)
			(layers "F.Cu" "F.Mask" "F.Paste")
			(roundrect_rratio 0.25)
			(net 79 "/Deserializer/PWDNB")
			(pinfunction "PWDNB")
			(pintype "passive")
		)
		(pad "12" smd roundrect
			(at -4 2.25 225)
			(size 0.8 0.3)
			(layers "F.Cu" "F.Mask" "F.Paste")
			(roundrect_rratio 0.25)
			(net 83 "/Connectors/MFP3")
			(pinfunction "MFP3")
			(pintype "passive")
		)
		(pad "13" smd roundrect
			(at -4 2.75 225)
			(size 0.8 0.3)
			(layers "F.Cu" "F.Mask" "F.Paste")
			(roundrect_rratio 0.25)
			(net 84 "/Connectors/MFP4")
			(pinfunction "MFP4")
			(pintype "passive")
		)
		(pad "14" smd roundrect
			(at -4 3.25 225)
			(size 0.8 0.3)
			(layers "F.Cu" "F.Mask" "F.Paste")
			(roundrect_rratio 0.25)
			(net 85 "/Connectors/MFP5")
			(pinfunction "MFP5")
			(pintype "passive")
		)
		(pad "15" smd roundrect
			(at -3.25 4 315)
			(size 0.8 0.3)
			(layers "F.Cu" "F.Mask" "F.Paste")
			(roundrect_rratio 0.25)
			(net 12 "/Deserializer/X1")
			(pinfunction "X1/OSC")
			(pintype "passive")
		)
		(pad "16" smd roundrect
			(at -2.75 4 315)
			(size 0.8 0.3)
			(layers "F.Cu" "F.Mask" "F.Paste")
			(roundrect_rratio 0.25)
			(net 75 "/Deserializer/X2")
			(pinfunction "X2")
			(pintype "passive")
		)
		(pad "17" smd roundrect
			(at -2.25 4 315)
			(size 0.8 0.3)
			(layers "F.Cu" "F.Mask" "F.Paste")
			(roundrect_rratio 0.25)
			(net 78 "/Deserializer/XRES")
			(pinfunction "XRES")
			(pintype "passive")
		)
		(pad "18" smd roundrect
			(at -1.75 4 315)
			(size 0.8 0.3)
			(layers "F.Cu" "F.Mask" "F.Paste")
			(roundrect_rratio 0.25)
			(net 14 "/Deserializer/SIOB_P")
			(pinfunction "SIOB_P")
			(pintype "passive")
		)
		(pad "19" smd roundrect
			(at -1.25 4.000001 315)
			(size 0.8 0.3)
			(layers "F.Cu" "F.Mask" "F.Paste")
			(roundrect_rratio 0.25)
			(net 20 "/Deserializer/SIOB_N")
			(pinfunction "SIOB_N")
			(pintype "passive")
		)
		(pad "20" smd roundrect
			(at -0.75 4 315)
			(size 0.8 0.3)
			(layers "F.Cu" "F.Mask" "F.Paste")
			(roundrect_rratio 0.25)
			(net 28 "/Deserializer/CAP_VDD")
			(pinfunction "CAP_VDD")
			(pintype "passive")
		)
		(pad "21" smd roundrect
			(at -0.25 4 315)
			(size 0.8 0.3)
			(layers "F.Cu" "F.Mask" "F.Paste")
			(roundrect_rratio 0.25)
			(net 26 "/Deserializer/VDD_1.8V")
			(pinfunction "VDD_1.8V")
			(pintype "passive")
		)
		(pad "22" smd roundrect
			(at 0.25 4 315)
			(size 0.8 0.3)
			(layers "F.Cu" "F.Mask" "F.Paste")
			(roundrect_rratio 0.25)
			(net 18 "/Deserializer/SIOA_N")
			(pinfunction "SIOA_N")
			(pintype "passive")
		)
		(pad "23" smd roundrect
			(at 0.75 4 315)
			(size 0.8 0.3)
			(layers "F.Cu" "F.Mask" "F.Paste")
			(roundrect_rratio 0.25)
			(net 13 "/Deserializer/SIOA_P")
			(pinfunction "SIOA_P")
			(pintype "passive")
		)
		(pad "24" smd roundrect
			(at 1.25 4.000001 315)
			(size 0.8 0.3)
			(layers "F.Cu" "F.Mask" "F.Paste")
			(roundrect_rratio 0.25)
			(net 146 "VDDIO")
			(pinfunction "VDDIO")
			(pintype "passive")
		)
		(pad "25" smd roundrect
			(at 1.75 4 315)
			(size 0.8 0.3)
			(layers "F.Cu" "F.Mask" "F.Paste")
			(roundrect_rratio 0.25)
			(net 77 "/Deserializer/CFG1")
			(pinfunction "CFG1/MFP6")
			(pintype "passive")
		)
		(pad "26" smd roundrect
			(at 2.25 4 315)
			(size 0.8 0.3)
			(layers "F.Cu" "F.Mask" "F.Paste")
			(roundrect_rratio 0.25)
			(net 86 "/Connectors/MFP7")
			(pinfunction "SDA1/MFP7")
			(pintype "passive")
		)
		(pad "27" smd roundrect
			(at 2.75 4 315)
			(size 0.8 0.3)
			(layers "F.Cu" "F.Mask" "F.Paste")
			(roundrect_rratio 0.25)
			(net 87 "/Connectors/MFP8")
			(pinfunction "SCL1/MFP8")
			(pintype "passive")
		)
		(pad "28" smd roundrect
			(at 3.25 4 315)
			(size 0.8 0.3)
			(layers "F.Cu" "F.Mask" "F.Paste")
			(roundrect_rratio 0.25)
			(net 88 "/Connectors/SDA")
			(pinfunction "SDA")
			(pintype "passive")
		)
		(pad "29" smd roundrect
			(at 4 3.25 225)
			(size 0.8 0.3)
			(layers "F.Cu" "F.Mask" "F.Paste")
			(roundrect_rratio 0.25)
			(net 121 "/Connectors/SCL")
			(pinfunction "SCL")
			(pintype "passive")
		)
		(pad "30" smd roundrect
			(at 4 2.75 225)
			(size 0.8 0.3)
			(layers "F.Cu" "F.Mask" "F.Paste")
			(roundrect_rratio 0.25)
			(net 29 "/Deserializer/VTERM")
			(pinfunction "VTERM")
			(pintype "passive")
		)
		(pad "31" smd roundrect
			(at 4 2.25 225)
			(size 0.8 0.3)
			(layers "F.Cu" "F.Mask" "F.Paste")
			(roundrect_rratio 0.25)
			(net 92 "/Connectors/CSI0.D0_P")
			(pinfunction "DA0_P")
			(pintype "passive")
		)
		(pad "32" smd roundrect
			(at 4 1.75 225)
			(size 0.8 0.3)
			(layers "F.Cu" "F.Mask" "F.Paste")
			(roundrect_rratio 0.25)
			(net 91 "/Connectors/CSI0.D0_N")
			(pinfunction "DA0_N")
			(pintype "passive")
		)
		(pad "33" smd roundrect
			(at 4.000001 1.25 225)
			(size 0.8 0.3)
			(layers "F.Cu" "F.Mask" "F.Paste")
			(roundrect_rratio 0.25)
			(net 136 "unconnected-(U7-CKC_P-Pad33)")
			(pinfunction "CKC_P")
			(pintype "passive+no_connect")
		)
		(pad "34" smd roundrect
			(at 4 0.75 225)
			(size 0.8 0.3)
			(layers "F.Cu" "F.Mask" "F.Paste")
			(roundrect_rratio 0.25)
			(net 137 "unconnected-(U7-CKC_N-Pad34)")
			(pinfunction "CKC_N")
			(pintype "passive+no_connect")
		)
		(pad "35" smd roundrect
			(at 4 0.25 225)
			(size 0.8 0.3)
			(layers "F.Cu" "F.Mask" "F.Paste")
			(roundrect_rratio 0.25)
			(net 90 "/Connectors/CSI0.D1_P")
			(pinfunction "DA1_P")
			(pintype "passive")
		)
		(pad "36" smd roundrect
			(at 4 -0.25 225)
			(size 0.8 0.3)
			(layers "F.Cu" "F.Mask" "F.Paste")
			(roundrect_rratio 0.25)
			(net 89 "/Connectors/CSI0.D1_N")
			(pinfunction "DA1_N")
			(pintype "passive")
		)
		(pad "37" smd roundrect
			(at 4 -0.75 225)
			(size 0.8 0.3)
			(layers "F.Cu" "F.Mask" "F.Paste")
			(roundrect_rratio 0.25)
			(net 102 "/Connectors/CSI0.D2_P")
			(pinfunction "DA2_P")
			(pintype "passive")
		)
		(pad "38" smd roundrect
			(at 4.000001 -1.25 225)
			(size 0.8 0.3)
			(layers "F.Cu" "F.Mask" "F.Paste")
			(roundrect_rratio 0.25)
			(net 101 "/Connectors/CSI0.D2_N")
			(pinfunction "DA2_N")
			(pintype "passive")
		)
		(pad "39" smd roundrect
			(at 4 -1.75 225)
			(size 0.8 0.3)
			(layers "F.Cu" "F.Mask" "F.Paste")
			(roundrect_rratio 0.25)
			(net 104 "/Connectors/CSI0.CLK_P")
			(pinfunction "CKA_P")
			(pintype "passive")
		)
		(pad "40" smd roundrect
			(at 4 -2.25 225)
			(size 0.8 0.3)
			(layers "F.Cu" "F.Mask" "F.Paste")
			(roundrect_rratio 0.25)
			(net 103 "/Connectors/CSI0.CLK_N")
			(pinfunction "CKA_N")
			(pintype "passive")
		)
		(pad "41" smd roundrect
			(at 4 -2.75 225)
			(size 0.8 0.3)
			(layers "F.Cu" "F.Mask" "F.Paste")
			(roundrect_rratio 0.25)
			(net 100 "/Connectors/CSI0.D3_P")
			(pinfunction "DA3_P")
			(pintype "passive")
		)
		(pad "42" smd roundrect
			(at 4 -3.25 225)
			(size 0.8 0.3)
			(layers "F.Cu" "F.Mask" "F.Paste")
			(roundrect_rratio 0.25)
			(net 99 "/Connectors/CSI0.D3_N")
			(pinfunction "DA3_N")
			(pintype "passive")
		)
		(pad "43" smd roundrect
			(at 3.25 -4 315)
			(size 0.8 0.3)
			(layers "F.Cu" "F.Mask" "F.Paste")
			(roundrect_rratio 0.25)
			(net 96 "/Connectors/CSI1.D0_P")
			(pinfunction "DB0_P")
			(pintype "passive")
		)
		(pad "44" smd roundrect
			(at 2.75 -4 315)
			(size 0.8 0.3)
			(layers "F.Cu" "F.Mask" "F.Paste")
			(roundrect_rratio 0.25)
			(net 95 "/Connectors/CSI1.D0_N")
			(pinfunction "DB0_N")
			(pintype "passive")
		)
		(pad "45" smd roundrect
			(at 2.25 -4 315)
			(size 0.8 0.3)
			(layers "F.Cu" "F.Mask" "F.Paste")
			(roundrect_rratio 0.25)
			(net 98 "/Connectors/CSI1.CLK_P")
			(pinfunction "CKB_P")
			(pintype "passive")
		)
		(pad "46" smd roundrect
			(at 1.75 -4 315)
			(size 0.8 0.3)
			(layers "F.Cu" "F.Mask" "F.Paste")
			(roundrect_rratio 0.25)
			(net 97 "/Connectors/CSI1.CLK_N")
			(pinfunction "CKB_N")
			(pintype "passive")
		)
		(pad "47" smd roundrect
			(at 1.25 -4.000001 315)
			(size 0.8 0.3)
			(layers "F.Cu" "F.Mask" "F.Paste")
			(roundrect_rratio 0.25)
			(net 94 "/Connectors/CSI1.D1_P")
			(pinfunction "DB1_P")
			(pintype "passive")
		)
		(pad "48" smd roundrect
			(at 0.75 -4 315)
			(size 0.8 0.3)
			(layers "F.Cu" "F.Mask" "F.Paste")
			(roundrect_rratio 0.25)
			(net 93 "/Connectors/CSI1.D1_N")
			(pinfunction "DB1_N")
			(pintype "passive")
		)
		(pad "49" smd roundrect
			(at 0.25 -4 315)
			(size 0.8 0.3)
			(layers "F.Cu" "F.Mask" "F.Paste")
			(roundrect_rratio 0.25)
			(net 108 "/Connectors/CSI1.D2_P")
			(pinfunction "DB2_P")
			(pintype "passive")
		)
		(pad "50" smd roundrect
			(at -0.25 -4 315)
			(size 0.8 0.3)
			(layers "F.Cu" "F.Mask" "F.Paste")
			(roundrect_rratio 0.25)
			(net 107 "/Connectors/CSI1.D2_N")
			(pinfunction "DB2_N")
			(pintype "passive")
		)
		(pad "51" smd roundrect
			(at -0.75 -4 315)
			(size 0.8 0.3)
			(layers "F.Cu" "F.Mask" "F.Paste")
			(roundrect_rratio 0.25)
			(net 138 "unconnected-(U7-CKF_P-Pad51)")
			(pinfunction "CKF_P")
			(pintype "passive+no_connect")
		)
		(pad "52" smd roundrect
			(at -1.25 -4.000001 315)
			(size 0.8 0.3)
			(layers "F.Cu" "F.Mask" "F.Paste")
			(roundrect_rratio 0.25)
			(net 139 "unconnected-(U7-CKF_N-Pad52)")
			(pinfunction "CKF_N")
			(pintype "passive+no_connect")
		)
		(pad "53" smd roundrect
			(at -1.75 -4 315)
			(size 0.8 0.3)
			(layers "F.Cu" "F.Mask" "F.Paste")
			(roundrect_rratio 0.25)
			(net 106 "/Connectors/CSI1.D3_P")
			(pinfunction "DB3_P")
			(pintype "passive")
		)
		(pad "54" smd roundrect
			(at -2.25 -4 315)
			(size 0.8 0.3)
			(layers "F.Cu" "F.Mask" "F.Paste")
			(roundrect_rratio 0.25)
			(net 105 "/Connectors/CSI1.D3_N")
			(pinfunction "DB3_N")
			(pintype "passive")
		)
		(pad "55" smd roundrect
			(at -2.75 -4 315)
			(size 0.8 0.3)
			(layers "F.Cu" "F.Mask" "F.Paste")
			(roundrect_rratio 0.25)
			(net 27 "/Deserializer/VDD")
			(pinfunction "VDD")
			(pintype "passive")
		)
		(pad "56" smd roundrect
			(at -3.25 -4 315)
			(size 0.8 0.3)
			(layers "F.Cu" "F.Mask" "F.Paste")
			(roundrect_rratio 0.25)
			(net 27 "/Deserializer/VDD")
			(pinfunction "VDD")
			(pintype "passive")
		)
		(pad "57" smd roundrect
			(at 0 0 225)
			(size 4.8 4.8)
			(layers "F.Cu" "F.Mask")
			(roundrect_rratio 0.1)
			(net 1 "GND")
			(pinfunction "GND")
			(pintype "passive")
		)
	)
)
